FILE_TYPE = CONNECTIVITY;
{Allegro Design Entry HDL 17.2-2016 S081 (4005846) 1/11/2022}
"PAGE_NUMBER" = 41;
0"NC";
1"VCCIO2\g";
2"PVCCA_AUX_PLD\g";
3"VCCIO4\g";
4"P3V3_AUX\g";
5"VCCIO3\g";
6"VCCIO1\g";
7"VCCIO0\g";
8"P3V3_AUX\g";
9"P3V3_AUX\g";
10"P3V3_AUX\g";
11"VCCIO5\g";
12"P3V3_AUX\g";
13"P3V3_AUX\g";
14"P3V3_AUX\g";
15"GND\g";
16"GND\g";
17"GND\g";
18"GND\g";
19"GND\g";
20"GND\g";
21"GND\g";
22"GND\g";
23"GND\g";
%"Q_CAP"
"1","(-4025,5850)","0","pure_quanta","I1";
;
VOLTAGE"25V"
TOLERANCE"10%"
PART_NUMBER"CH4104K1B00"
MATERIAL"X7R"
VALUE"0.1UF"
PACK_TYPE"0402"
CDS_LIB"pure_quanta"
$LOCATION"C242"
CDS_LOCATION"C242"
$SEC"1"
CDS_SEC"1";
"B"
$PN"2"23;
"A"
$PN"1"7;
%"UNIVERSAL_GND"
"1","(-7900,5425)","0","logical_power","I100";
;
CDS_LIB"logical_power"
ROOM"IO_SLOT"
HDL_POWER"GND";
"A"16;
%"Q_CAP"
"1","(-7900,5700)","0","pure_quanta","I101";
;
PACK_TYPE"C0603"
PART_NUMBER"CH6103ME902"
VOLTAGE"16V"
VALUE"10UF"
MATERIAL"X6S"
TOLERANCE"20%"
CDS_LIB"pure_quanta"
$LOCATION"C194"
CDS_LOCATION"C194"
$SEC"1"
CDS_SEC"1";
"B"
$PN"2"16;
"A"
$PN"1"12;
%"UNIVERSAL_POWER"
"1","(-6025,2500)","0","logical_power","I104";
;
HDL_POWER"P3V3_AUX"
CDS_LIB"logical_power";
"A"14;
%"Q_INDUCTOR"
"1","(-5550,2200)","0","pure_quanta","I107";
;
VALUE"BLM18EG121SN1D/2A"
PART_NUMBER"CX8EG121000"
PACK_TYPE"SMLF"
MATERIAL"IND"
CDS_LIB"pure_quanta"
NEEDS_NO_SIZE"TRUE"
$LOCATION"L19"
CDS_LOCATION"L19"
$SEC"1"
CDS_SEC"1";
"1"
$PN"1"14;
"2"
$PN"2"2;
%"Q_CAP"
"1","(-4650,1975)","0","pure_quanta","I108";
;
PACK_TYPE"C0402"
TOLERANCE"10%"
VOLTAGE"25V"
PART_NUMBER"CH5104KEB02"
MATERIAL"X6S"
VALUE"1UF"
SEC_TYPE"C0402"
CDS_LIB"pure_quanta"
$LOCATION"C176"
CDS_LOCATION"C176"
SEC"1";
"B"
$PN"2"17;
"A"
$PN"1"2;
%"Q_CAP"
"1","(-4075,1950)","0","pure_quanta","I109";
;
TOLERANCE"10%"
VOLTAGE"25V"
VALUE"0.1UF"
MATERIAL"X7R"
PACK_TYPE"0402"
PART_NUMBER"CH4104K1B00"
SEC_TYPE"0402"
CDS_LIB"pure_quanta"
$LOCATION"C193"
CDS_LOCATION"C193"
SEC"1";
"B"
$PN"2"17;
"A"
$PN"1"2;
%"UNIVERSAL_POWER"
"1","(-5575,6425)","0","logical_power","I11";
;
HDL_POWER"P3V3_AUX"
CDS_LIB"logical_power";
"A"13;
%"UNIVERSAL_GND"
"1","(-2600,1525)","0","logical_power","I112";
;
HDL_POWER"GND"
CDS_LIB"logical_power"
ROOM"IO_SLOT";
"A"17;
%"UNIVERSAL_POWER"
"1","(-250,2250)","0","logical_power","I114";
;
HDL_POWER"PVCCA_AUX_PLD"
CDS_LIB"logical_power";
"A"2;
%"Q_CAP"
"1","(-3450,1950)","0","pure_quanta","I115";
;
PART_NUMBER"CH4104K1B00"
TOLERANCE"10%"
VOLTAGE"25V"
VALUE"0.1UF"
MATERIAL"X7R"
PACK_TYPE"0402"
CDS_LIB"pure_quanta"
$LOCATION"C250"
CDS_LOCATION"C250"
$SEC"1"
CDS_SEC"1";
"B"
$PN"2"17;
"A"
$PN"1"2;
%"Q_CAP"
"1","(-2875,1950)","0","pure_quanta","I116";
;
MATERIAL"X7R"
TOLERANCE"10%"
VALUE"0.1UF"
VOLTAGE"25V"
PACK_TYPE"0402"
PART_NUMBER"CH4104K1B00"
CDS_LIB"pure_quanta"
$LOCATION"C190"
CDS_LOCATION"C190"
$SEC"1"
CDS_SEC"1";
"B"
$PN"2"17;
"A"
$PN"1"2;
%"Q_CAP"
"1","(-2325,1950)","0","pure_quanta","I117";
;
VOLTAGE"25V"
MATERIAL"X7R"
TOLERANCE"10%"
PART_NUMBER"CH4104K1B00"
PACK_TYPE"0402"
VALUE"0.1UF"
CDS_LIB"pure_quanta"
$LOCATION"C263"
CDS_LOCATION"C263"
$SEC"1"
CDS_SEC"1";
"B"
$PN"2"17;
"A"
$PN"1"2;
%"Q_CAP"
"1","(-1200,1950)","0","pure_quanta","I118";
;
VOLTAGE"25V"
PART_NUMBER"CH4104K1B00"
PACK_TYPE"0402"
MATERIAL"X7R"
TOLERANCE"10%"
VALUE"0.1UF"
CDS_LIB"pure_quanta"
$LOCATION"C269"
CDS_LOCATION"C269"
$SEC"1"
CDS_SEC"1";
"B"
$PN"2"17;
"A"
$PN"1"2;
%"Q_CAP"
"1","(-1775,1950)","0","pure_quanta","I119";
;
PACK_TYPE"0402"
PART_NUMBER"CH4104K1B00"
VALUE"0.1UF"
VOLTAGE"25V"
TOLERANCE"10%"
MATERIAL"X7R"
CDS_LIB"pure_quanta"
$LOCATION"C266"
CDS_LOCATION"C266"
$SEC"1"
CDS_SEC"1";
"B"
$PN"2"17;
"A"
$PN"1"2;
%"Q_CAP"
"1","(-5225,1950)","0","pure_quanta","I122";
;
PACK_TYPE"C0603"
PART_NUMBER"CH6103ME902"
VOLTAGE"16V"
TOLERANCE"20%"
MATERIAL"X6S"
VALUE"10UF"
CDS_LIB"pure_quanta"
$LOCATION"C163"
CDS_LOCATION"C163"
$SEC"1"
CDS_SEC"1";
"B"
$PN"2"17;
"A"
$PN"1"2;
%"Q_CAP"
"1","(-575,1950)","0","pure_quanta","I123";
;
VOLTAGE"50V"
TOLERANCE"10%"
PACK_TYPE"C0402"
PART_NUMBER"CH31006KB18"
VALUE"0.01UF"
MATERIAL"EMPTY"
CDS_LIB"pure_quanta"
$LOCATION"C286"
CDS_LOCATION"C286"
$SEC"1"
CDS_SEC"1";
"B"
$PN"2"17;
"A"
$PN"1"2;
%"Q_CAP"
"1","(-1550,3575)","0","pure_quanta","I124";
;
VOLTAGE"50V"
TOLERANCE"10%"
VALUE"0.01UF"
PACK_TYPE"C0402"
PART_NUMBER"CH31006KB18"
MATERIAL"EMPTY"
CDS_LIB"pure_quanta"
$LOCATION"C285"
CDS_LOCATION"C285"
$SEC"1"
CDS_SEC"1";
"B"
$PN"2"21;
"A"
$PN"1"1;
%"Q_CAP"
"1","(-1575,4675)","0","pure_quanta","I125";
;
VOLTAGE"50V"
PACK_TYPE"C0402"
PART_NUMBER"CH31006KB18"
TOLERANCE"10%"
VALUE"0.01UF"
MATERIAL"EMPTY"
CDS_LIB"pure_quanta"
$LOCATION"C281"
CDS_LOCATION"C281"
$SEC"1"
CDS_SEC"1";
"B"
$PN"2"22;
"A"
$PN"1"6;
%"Q_CAP"
"1","(-1550,5850)","0","pure_quanta","I126";
;
VOLTAGE"50V"
TOLERANCE"10%"
VALUE"0.01UF"
PACK_TYPE"C0402"
PART_NUMBER"CH31006KB18"
MATERIAL"EMPTY"
CDS_LIB"pure_quanta"
$LOCATION"C283"
CDS_LOCATION"C283"
$SEC"1"
CDS_SEC"1";
"B"
$PN"2"23;
"A"
$PN"1"7;
%"UNIVERSAL_POWER"
"1","(-5575,5225)","0","logical_power","I18";
;
HDL_POWER"P3V3_AUX"
CDS_LIB"logical_power";
"A"9;
%"UNIVERSAL_GND"
"1","(-2625,4275)","0","logical_power","I24";
;
CDS_LIB"logical_power"
ROOM"IO_SLOT"
HDL_POWER"GND";
"A"22;
%"UNIVERSAL_POWER"
"1","(-425,5025)","0","logical_power","I26";
;
HDL_POWER"VCCIO1"
CDS_LIB"logical_power";
"A"6;
%"UNIVERSAL_POWER"
"1","(-750,3925)","0","logical_power","I27";
;
HDL_POWER"VCCIO2"
CDS_LIB"logical_power";
"A"1;
%"UNIVERSAL_GND"
"1","(-2625,3175)","0","logical_power","I29";
;
CDS_LIB"logical_power"
HDL_POWER"GND"
ROOM"IO_SLOT";
"A"21;
%"UNIVERSAL_POWER"
"1","(-5575,4125)","0","logical_power","I35";
;
HDL_POWER"P3V3_AUX"
CDS_LIB"logical_power";
"A"4;
%"UNIVERSAL_POWER"
"1","(-6825,3575)","0","logical_power","I40";
;
HDL_POWER"VCCIO3"
CDS_LIB"logical_power";
"A"5;
%"UNIVERSAL_GND"
"1","(-7200,2825)","0","logical_power","I42";
;
HDL_POWER"GND"
ROOM"IO_SLOT"
CDS_LIB"logical_power";
"A"19;
%"UNIVERSAL_POWER"
"1","(-8725,3800)","0","logical_power","I48";
;
HDL_POWER"P3V3_AUX"
CDS_LIB"logical_power";
"A"10;
%"UNIVERSAL_POWER"
"1","(-6725,4825)","0","logical_power","I53";
;
HDL_POWER"VCCIO4"
CDS_LIB"logical_power";
"A"3;
%"UNIVERSAL_GND"
"1","(-7100,4075)","0","logical_power","I55";
;
CDS_LIB"logical_power"
HDL_POWER"GND"
ROOM"IO_SLOT";
"A"20;
%"UNIVERSAL_POWER"
"1","(-575,6175)","0","logical_power","I6";
;
HDL_POWER"VCCIO0"
CDS_LIB"logical_power";
"A"7;
%"UNIVERSAL_POWER"
"1","(-8775,5025)","0","logical_power","I61";
;
HDL_POWER"P3V3_AUX"
CDS_LIB"logical_power";
"A"8;
%"UNIVERSAL_POWER"
"1","(-6775,2600)","0","logical_power","I66";
;
HDL_POWER"VCCIO5"
CDS_LIB"logical_power";
"A"11;
%"UNIVERSAL_GND"
"1","(-7150,1850)","0","logical_power","I68";
;
CDS_LIB"logical_power"
ROOM"IO_SLOT"
HDL_POWER"GND";
"A"18;
%"UNIVERSAL_GND"
"1","(-2600,5425)","0","logical_power","I7";
;
CDS_LIB"logical_power"
ROOM"IO_SLOT"
HDL_POWER"GND";
"A"23;
%"Q_RES"
"1","(-5100,6075)","0","pure_quanta","I71";
;
VALUE"0"
TOLERANCE"5%"
WATTAGE"1/16W"
PART_NUMBER"CS00002JB13"
MATERIAL"CHIP"
PACK_TYPE"0402LF"
CDS_LIB"pure_quanta"
$LOCATION"R305"
CDS_LOCATION"R305"
$SEC"1"
CDS_SEC"1";
"B"
$PN"2"7;
"A"
$PN"1"13;
%"Q_RES"
"1","(-5125,4925)","0","pure_quanta","I72";
;
VALUE"0"
TOLERANCE"5%"
WATTAGE"1/16W"
MATERIAL"CHIP"
PACK_TYPE"0402LF"
PART_NUMBER"CS00002JB13"
CDS_LIB"pure_quanta"
$LOCATION"R525"
CDS_LOCATION"R525"
$SEC"1"
CDS_SEC"1";
"B"
$PN"2"6;
"A"
$PN"1"9;
%"Q_RES"
"1","(-5125,3825)","0","pure_quanta","I73";
;
TOLERANCE"5%"
VALUE"0"
WATTAGE"1/16W"
MATERIAL"CHIP"
PACK_TYPE"0402LF"
PART_NUMBER"CS00002JB13"
CDS_LIB"pure_quanta"
$LOCATION"R304"
CDS_LOCATION"R304"
$SEC"1"
CDS_SEC"1";
"B"
$PN"2"1;
"A"
$PN"1"4;
%"Q_RES"
"1","(-8250,3475)","0","pure_quanta","I74";
;
PART_NUMBER"CS00002JB13"
PACK_TYPE"0402LF"
MATERIAL"CHIP"
WATTAGE"1/16W"
TOLERANCE"5%"
VALUE"0"
CDS_LIB"pure_quanta"
$LOCATION"R308"
CDS_LOCATION"R308"
$SEC"1"
CDS_SEC"1";
"B"
$PN"2"5;
"A"
$PN"1"10;
%"Q_RES"
"1","(-8200,2500)","0","pure_quanta","I75";
;
PART_NUMBER"CS00002JB13"
TOLERANCE"5%"
MATERIAL"CHIP"
PACK_TYPE"0402LF"
WATTAGE"1/16W"
VALUE"0"
CDS_LIB"pure_quanta"
$LOCATION"R301"
CDS_LOCATION"R301"
$SEC"1"
CDS_SEC"1";
"B"
$PN"2"11;
"A"
$PN"1"10;
%"Q_RES"
"1","(-8575,4725)","0","pure_quanta","I76";
;
TOLERANCE"5%"
VALUE"0"
PACK_TYPE"0402LF"
MATERIAL"CHIP"
WATTAGE"1/16W"
PART_NUMBER"CS00002JB13"
CDS_LIB"pure_quanta"
$LOCATION"R307"
CDS_LOCATION"R307"
$SEC"1"
CDS_SEC"1";
"B"
$PN"2"3;
"A"
$PN"1"8;
%"Q_CAP"
"1","(-3400,5850)","0","pure_quanta","I77";
;
PART_NUMBER"CH4104K1B00"
VALUE"0.1UF"
VOLTAGE"25V"
TOLERANCE"10%"
MATERIAL"X7R"
PACK_TYPE"0402"
CDS_LIB"pure_quanta"
$LOCATION"C247"
CDS_LOCATION"C247"
$SEC"1"
CDS_SEC"1";
"B"
$PN"2"23;
"A"
$PN"1"7;
%"Q_CAP"
"1","(-2825,5850)","0","pure_quanta","I78";
;
TOLERANCE"10%"
PART_NUMBER"CH4104K1B00"
VOLTAGE"25V"
VALUE"0.1UF"
PACK_TYPE"0402"
MATERIAL"X7R"
CDS_LIB"pure_quanta"
$LOCATION"C189"
CDS_LOCATION"C189"
$SEC"1"
CDS_SEC"1";
"B"
$PN"2"23;
"A"
$PN"1"7;
%"Q_CAP"
"1","(-2250,5850)","0","pure_quanta","I79";
;
VALUE"0.1UF"
MATERIAL"X7R"
TOLERANCE"10%"
VOLTAGE"25V"
PART_NUMBER"CH4104K1B00"
PACK_TYPE"0402"
CDS_LIB"pure_quanta"
$LOCATION"C261"
CDS_LOCATION"C261"
$SEC"1"
CDS_SEC"1";
"B"
$PN"2"23;
"A"
$PN"1"7;
%"Q_CAP"
"1","(-4700,5875)","0","pure_quanta","I8";
;
PART_NUMBER"CH5104KEB02"
PACK_TYPE"C0402"
VALUE"1UF"
VOLTAGE"25V"
TOLERANCE"10%"
MATERIAL"X6S"
CDS_LIB"pure_quanta"
$LOCATION"C166"
CDS_LOCATION"C166"
$SEC"1"
CDS_SEC"1";
"B"
$PN"2"23;
"A"
$PN"1"7;
%"Q_CAP"
"1","(-4050,4700)","0","pure_quanta","I80";
;
VALUE"0.1UF"
MATERIAL"X7R"
TOLERANCE"10%"
VOLTAGE"25V"
PACK_TYPE"0402"
PART_NUMBER"CH4104K1B00"
CDS_LIB"pure_quanta"
$LOCATION"C167"
CDS_LOCATION"C167"
$SEC"1"
CDS_SEC"1";
"B"
$PN"2"22;
"A"
$PN"1"6;
%"Q_CAP"
"1","(-3450,4700)","0","pure_quanta","I81";
;
PACK_TYPE"0402"
MATERIAL"X7R"
TOLERANCE"10%"
VOLTAGE"25V"
VALUE"0.1UF"
PART_NUMBER"CH4104K1B00"
CDS_LIB"pure_quanta"
$LOCATION"C243"
CDS_LOCATION"C243"
$SEC"1"
CDS_SEC"1";
"B"
$PN"2"22;
"A"
$PN"1"6;
%"Q_CAP"
"1","(-2875,4700)","0","pure_quanta","I82";
;
TOLERANCE"10%"
PART_NUMBER"CH4104K1B00"
PACK_TYPE"0402"
MATERIAL"X7R"
VALUE"0.1UF"
VOLTAGE"25V"
CDS_LIB"pure_quanta"
$LOCATION"C254"
CDS_LOCATION"C254"
$SEC"1"
CDS_SEC"1";
"B"
$PN"2"22;
"A"
$PN"1"6;
%"Q_CAP"
"1","(-2300,4700)","0","pure_quanta","I83";
;
PART_NUMBER"CH4104K1B00"
PACK_TYPE"0402"
MATERIAL"X7R"
VOLTAGE"25V"
TOLERANCE"10%"
VALUE"0.1UF"
CDS_LIB"pure_quanta"
$LOCATION"C141"
CDS_LOCATION"C141"
$SEC"1"
CDS_SEC"1";
"B"
$PN"2"22;
"A"
$PN"1"6;
%"Q_CAP"
"1","(-4050,3600)","0","pure_quanta","I84";
;
PART_NUMBER"CH4104K1B00"
MATERIAL"X7R"
TOLERANCE"10%"
PACK_TYPE"0402"
VALUE"0.1UF"
VOLTAGE"25V"
CDS_LIB"pure_quanta"
$LOCATION"C187"
CDS_LOCATION"C187"
$SEC"1"
CDS_SEC"1";
"B"
$PN"2"21;
"A"
$PN"1"1;
%"Q_CAP"
"1","(-3425,3600)","0","pure_quanta","I85";
;
PART_NUMBER"CH4104K1B00"
VOLTAGE"25V"
VALUE"0.1UF"
TOLERANCE"10%"
MATERIAL"X7R"
PACK_TYPE"0402"
CDS_LIB"pure_quanta"
$LOCATION"C245"
CDS_LOCATION"C245"
$SEC"1"
CDS_SEC"1";
"B"
$PN"2"21;
"A"
$PN"1"1;
%"Q_CAP"
"1","(-2850,3600)","0","pure_quanta","I86";
;
VALUE"0.1UF"
MATERIAL"X7R"
TOLERANCE"10%"
VOLTAGE"25V"
PART_NUMBER"CH4104K1B00"
PACK_TYPE"0402"
CDS_LIB"pure_quanta"
$LOCATION"C188"
CDS_LOCATION"C188"
$SEC"1"
CDS_SEC"1";
"B"
$PN"2"21;
"A"
$PN"1"1;
%"Q_CAP"
"1","(-2275,3600)","0","pure_quanta","I87";
;
TOLERANCE"10%"
VALUE"0.1UF"
PART_NUMBER"CH4104K1B00"
PACK_TYPE"0402"
VOLTAGE"25V"
MATERIAL"X7R"
CDS_LIB"pure_quanta"
$LOCATION"C260"
CDS_LOCATION"C260"
$SEC"1"
CDS_SEC"1";
"B"
$PN"2"21;
"A"
$PN"1"1;
%"Q_CAP"
"1","(-7200,3250)","0","pure_quanta","I88";
;
PART_NUMBER"CH4104K1B00"
VALUE"0.1UF"
MATERIAL"X7R"
TOLERANCE"10%"
VOLTAGE"25V"
PACK_TYPE"0402"
CDS_LIB"pure_quanta"
$LOCATION"C152"
CDS_LOCATION"C152"
$SEC"1"
CDS_SEC"1";
"B"
$PN"2"19;
"A"
$PN"1"5;
%"Q_CAP"
"1","(-7150,2275)","0","pure_quanta","I89";
;
VOLTAGE"25V"
PACK_TYPE"0402"
MATERIAL"X7R"
TOLERANCE"10%"
VALUE"0.1UF"
PART_NUMBER"CH4104K1B00"
CDS_LIB"pure_quanta"
$LOCATION"C160"
CDS_LOCATION"C160"
$SEC"1"
CDS_SEC"1";
"B"
$PN"2"18;
"A"
$PN"1"11;
%"Q_CAP"
"1","(-7525,4500)","0","pure_quanta","I90";
;
PART_NUMBER"CH4104K1B00"
MATERIAL"X7R"
TOLERANCE"10%"
VOLTAGE"25V"
VALUE"0.1UF"
PACK_TYPE"0402"
CDS_LIB"pure_quanta"
$LOCATION"C220"
CDS_LOCATION"C220"
$SEC"1"
CDS_SEC"1";
"B"
$PN"2"20;
"A"
$PN"1"3;
%"Q_CAP"
"1","(-7100,4500)","0","pure_quanta","I91";
;
MATERIAL"X7R"
PART_NUMBER"CH4104K1B00"
VALUE"0.1UF"
TOLERANCE"10%"
PACK_TYPE"0402"
VOLTAGE"25V"
CDS_LIB"pure_quanta"
$LOCATION"C162"
CDS_LOCATION"C162"
$SEC"1"
CDS_SEC"1";
"B"
$PN"2"20;
"A"
$PN"1"3;
%"Q_CAP"
"1","(-4725,4725)","0","pure_quanta","I92";
;
PACK_TYPE"C0402"
PART_NUMBER"CH5104KEB02"
TOLERANCE"10%"
VALUE"1UF"
VOLTAGE"25V"
MATERIAL"X6S"
CDS_LIB"pure_quanta"
$LOCATION"C164"
CDS_LOCATION"C164"
$SEC"1"
CDS_SEC"1";
"B"
$PN"2"22;
"A"
$PN"1"6;
%"Q_CAP"
"1","(-4725,3625)","0","pure_quanta","I93";
;
PART_NUMBER"CH5104KEB02"
PACK_TYPE"C0402"
TOLERANCE"10%"
MATERIAL"X6S"
VALUE"1UF"
VOLTAGE"25V"
CDS_LIB"pure_quanta"
$LOCATION"C165"
CDS_LOCATION"C165"
$SEC"1"
CDS_SEC"1";
"B"
$PN"2"21;
"A"
$PN"1"1;
%"Q_CAP"
"1","(-7850,3275)","0","pure_quanta","I94";
;
PART_NUMBER"CH5104KEB02"
PACK_TYPE"C0402"
MATERIAL"X6S"
TOLERANCE"10%"
VOLTAGE"25V"
VALUE"1UF"
CDS_LIB"pure_quanta"
$LOCATION"C216"
CDS_LOCATION"C216"
$SEC"1"
CDS_SEC"1";
"B"
$PN"2"19;
"A"
$PN"1"5;
%"Q_CAP"
"1","(-7800,2300)","0","pure_quanta","I95";
;
VALUE"1UF"
VOLTAGE"25V"
TOLERANCE"10%"
MATERIAL"X6S"
PART_NUMBER"CH5104KEB02"
PACK_TYPE"C0402"
CDS_LIB"pure_quanta"
$LOCATION"C218"
CDS_LOCATION"C218"
$SEC"1"
CDS_SEC"1";
"B"
$PN"2"18;
"A"
$PN"1"11;
%"Q_CAP"
"1","(-8175,4525)","0","pure_quanta","I96";
;
VOLTAGE"25V"
TOLERANCE"10%"
PACK_TYPE"C0402"
MATERIAL"X6S"
VALUE"1UF"
PART_NUMBER"CH5104KEB02"
CDS_LIB"pure_quanta"
$LOCATION"C195"
CDS_LOCATION"C195"
$SEC"1"
CDS_SEC"1";
"B"
$PN"2"20;
"A"
$PN"1"3;
%"UNIVERSAL_POWER"
"1","(-8800,6375)","0","logical_power","I97";
;
HDL_POWER"P3V3_AUX"
CDS_LIB"logical_power";
"A"12;
%"UNIVERSAL_GND"
"1","(-8800,5450)","0","logical_power","I98";
;
CDS_LIB"logical_power"
ROOM"IO_SLOT"
HDL_POWER"GND";
"A"15;
%"Q_CAP"
"1","(-8800,5800)","0","pure_quanta","I99";
;
PACK_TYPE"C0402"
MATERIAL"X6S"
TOLERANCE"10%"
PART_NUMBER"CH5104KEB02"
VOLTAGE"25V"
VALUE"1UF"
CDS_LIB"pure_quanta"
SEC_TYPE"C0402"
$LOCATION"C145"
CDS_LOCATION"C145"
SEC"1";
"B"
$PN"2"15;
"A"
$PN"1"12;
END.
